# BASEBOARD_FAB2 (Tioga Pass) — schematic netlist excerpt (pin names and nets, part order shuffled) for the footprints in the layout excerpt that follows; sources: Cadence DE-HDL packaged netlist, KiCad conversion of Wiwynn_Tioga_Pass_MB.brd

CT46  CAP_A  0.1UF 16V 10% X7R  pkg 0402V  page 219 : A = VR_PVDDQ_DEF_AIREF2 ; B = GND
R4D67  RES  0.0 5% CHIP  pkg 0402  page 201 : A = SVID_VALERT_VCCIN_CPU0 ; B = SVID_ALERT0_CPU0_R_N
R9E7  RES  3.32K 1% CHIP  pkg 0402  page 139 : A = P3V3_STBY ; B = IRQ_LOM_ALERT_N

(kicad_pcb
	(version 20260206)
	(generator "pcbnew")
	(generator_version "10.0")
	(general
		(thickness 1.6)
		(legacy_teardrops no)
	)
	(paper "A4")
	(title_block
		(title "Wiwynn_Tioga_Pass_MB.brd")
		(comment 1 "Tioga Pass / footprints 1006-1008 of 4770")
	)
	(layers
		(0 "F.Cu" signal "TOP")
		(4 "In1.Cu" signal "L2GND")
		(6 "In2.Cu" signal "L3")
		(8 "In3.Cu" signal "L4GND")
		(10 "In4.Cu" signal "L5")
		(12 "In5.Cu" signal "L6GND")
		(14 "In6.Cu" signal "L7VCC")
		(16 "In7.Cu" signal "L8VCC")
		(18 "In8.Cu" signal "L9GND")
		(20 "In9.Cu" signal "L10")
		(22 "In10.Cu" signal "L11GND")
		(24 "In11.Cu" signal "L12")
		(26 "In12.Cu" signal "L13GND")
		(2 "B.Cu" signal "BOTTOM")
		(9 "F.Adhes" user "F.Adhesive")
		(11 "B.Adhes" user "B.Adhesive")
		(13 "F.Paste" user "Package Geometry/Pastemask Top")
		(15 "B.Paste" user "Package Geometry/Pastemask Bottom")
		(5 "F.SilkS" user "Ref Des/Silkscreen Top")
		(7 "B.SilkS" user "Ref Des/Silkscreen Bottom")
		(1 "F.Mask" user "Board Geometry/Soldermask Top")
		(3 "B.Mask" user "Board Geometry/Soldermask Bottom")
		(17 "Dwgs.User" user "User.Drawings")
		(19 "Cmts.User" user "User.Comments")
		(21 "Eco1.User" user "User.Eco1")
		(23 "Eco2.User" user "User.Eco2")
		(25 "Edge.Cuts" user "Board Geometry/Outline")
		(27 "Margin" user)
		(31 "F.CrtYd" user "Package Geometry/Place Bound Top")
		(29 "B.CrtYd" user "Package Geometry/Place Bound Bottom")
		(35 "F.Fab" user "Ref Des/Assembly Top")
		(33 "B.Fab" user "Ref Des/Assembly Bottom")
	)
	(footprint ""
		(layer "F.Cu")
		(at 351.83699 -148.646388 -90)
		(property "Reference" "CT46"
			(at 7.03707 4.2418 0)
			(unlocked yes)
			(layer "F.SilkS")
			(effects
				(font
					(size 0.7874 0.5842)
					(thickness 0.1524)
				)
				(justify left)
			)
		)
		(property "Value" ""
			(at 0 0 270)
			(layer "F.Fab")
			(effects
				(font
					(size 1.27 1.27)
				)
			)
		)
		(duplicate_pad_numbers_are_jumpers no)
		(fp_poly
			(pts
				(xy 0.3048 -0.1016) (xy 0.3048 0.9906) (xy -0.3048 0.9906) (xy -0.3048 -0.1016)
			)
			(stroke
				(width 0)
				(type default)
			)
			(fill no)
			(layer "F.CrtYd")
		)
		(fp_line
			(start -0.3048 0.9906)
			(end 0.3048 0.9906)
			(stroke
				(width 0.1)
				(type default)
			)
			(layer "F.Fab")
		)
		(fp_line
			(start 0.3048 0.9906)
			(end 0.3048 -0.1016)
			(stroke
				(width 0.1)
				(type default)
			)
			(layer "F.Fab")
		)
		(fp_line
			(start -0.3048 -0.1016)
			(end -0.3048 0.9906)
			(stroke
				(width 0.1)
				(type default)
			)
			(layer "F.Fab")
		)
		(fp_line
			(start 0.3048 -0.1016)
			(end -0.3048 -0.1016)
			(stroke
				(width 0.1)
				(type default)
			)
			(layer "F.Fab")
		)
		(pad "1" smd rect
			(at 0 0 270)
			(size 0.508 0.508)
			(layers "F.Cu" "F.Mask" "F.Paste")
			(net "VR_PVDDQ_DEF_AIREF2")
		)
		(pad "2" smd rect
			(at 0 0.889 270)
			(size 0.508 0.508)
			(layers "F.Cu" "F.Mask" "F.Paste")
			(net "GND")
		)
		(zone
			(layer "F.Cu")
			(hatch none 0.5)
			(connect_pads
				(clearance 0)
			)
			(min_thickness 0.25)
			(keepout
				(tracks not_allowed)
				(vias allowed)
				(pads allowed)
				(copperpour not_allowed)
				(footprints allowed)
			)
			(placement
				(enabled no)
				(sheetname "")
			)
			(fill
				(thermal_gap 0.5)
				(thermal_bridge_width 0.5)
				(island_removal_mode 0)
			)
			(polygon
				(pts
					(xy 351.20199 -148.900388) (xy 351.20199 -148.392388) (xy 351.58299 -148.392388) (xy 351.58299 -148.900388)
				)
			)
		)
		(zone
			(layer "F.Cu")
			(hatch none 0.5)
			(connect_pads
				(clearance 0)
			)
			(min_thickness 0.25)
			(keepout
				(tracks allowed)
				(vias not_allowed)
				(pads allowed)
				(copperpour not_allowed)
				(footprints allowed)
			)
			(placement
				(enabled no)
				(sheetname "")
			)
			(fill
				(thermal_gap 0.5)
				(thermal_bridge_width 0.5)
				(island_removal_mode 0)
			)
			(polygon
				(pts
					(xy 351.58299 -148.900388) (xy 351.58299 -148.392388) (xy 351.20199 -148.392388) (xy 351.20199 -148.900388)
				)
			)
		)
	)
	(footprint ""
		(layer "F.Cu")
		(at 184.531 -65.024)
		(property "Reference" "R4D67"
			(at 0 0 0)
			(layer "F.SilkS")
			(hide yes)
			(effects
				(font
					(size 1.27 1.27)
				)
			)
		)
		(property "Value" ""
			(at 0 0 0)
			(layer "F.Fab")
			(effects
				(font
					(size 1.27 1.27)
				)
			)
		)
		(duplicate_pad_numbers_are_jumpers no)
		(fp_rect
			(start -0.2794 0.9906)
			(end 0.2794 -0.1016)
			(stroke
				(width 0)
				(type default)
			)
			(fill no)
			(layer "F.CrtYd")
		)
		(fp_line
			(start -0.2794 -0.1016)
			(end -0.2794 0.9906)
			(stroke
				(width 0.1)
				(type default)
			)
			(layer "F.Fab")
		)
		(fp_line
			(start -0.2794 0.9906)
			(end 0.2794 0.9906)
			(stroke
				(width 0.1)
				(type default)
			)
			(layer "F.Fab")
		)
		(fp_line
			(start 0.2794 -0.1016)
			(end -0.2794 -0.1016)
			(stroke
				(width 0.1)
				(type default)
			)
			(layer "F.Fab")
		)
		(fp_line
			(start 0.2794 0.9906)
			(end 0.2794 -0.1016)
			(stroke
				(width 0.1)
				(type default)
			)
			(layer "F.Fab")
		)
		(pad "1" smd rect
			(at 0 0)
			(size 0.508 0.508)
			(layers "F.Cu" "F.Mask" "F.Paste")
			(net "SVID_VALERT_VCCIN_CPU0")
		)
		(pad "2" smd rect
			(at 0 0.889)
			(size 0.508 0.508)
			(layers "F.Cu" "F.Mask" "F.Paste")
			(net "SVID_ALERT0_CPU0_R_N")
		)
		(zone
			(layer "F.Cu")
			(hatch none 0.5)
			(connect_pads
				(clearance 0)
			)
			(min_thickness 0.25)
			(keepout
				(tracks allowed)
				(vias not_allowed)
				(pads allowed)
				(copperpour not_allowed)
				(footprints allowed)
			)
			(placement
				(enabled no)
				(sheetname "")
			)
			(fill
				(thermal_gap 0.5)
				(thermal_bridge_width 0.5)
				(island_removal_mode 0)
			)
			(polygon
				(pts
					(xy 184.277 -64.389) (xy 184.785 -64.389) (xy 184.785 -64.77) (xy 184.277 -64.77)
				)
			)
		)
		(zone
			(layer "F.Cu")
			(hatch none 0.5)
			(connect_pads
				(clearance 0)
			)
			(min_thickness 0.25)
			(keepout
				(tracks not_allowed)
				(vias allowed)
				(pads allowed)
				(copperpour not_allowed)
				(footprints allowed)
			)
			(placement
				(enabled no)
				(sheetname "")
			)
			(fill
				(thermal_gap 0.5)
				(thermal_bridge_width 0.5)
				(island_removal_mode 0)
			)
			(polygon
				(pts
					(xy 184.277 -64.389) (xy 184.785 -64.389) (xy 184.785 -64.77) (xy 184.277 -64.77)
				)
			)
		)
	)
	(footprint ""
		(layer "F.Cu")
		(at 477.8756 -48.9839)
		(property "Reference" "R9E7"
			(at 0 0 0)
			(layer "F.SilkS")
			(hide yes)
			(effects
				(font
					(size 1.27 1.27)
				)
			)
		)
		(property "Value" ""
			(at 0 0 0)
			(layer "F.Fab")
			(effects
				(font
					(size 1.27 1.27)
				)
			)
		)
		(duplicate_pad_numbers_are_jumpers no)
		(fp_poly
			(pts
				(xy -0.2794 -0.1016) (xy 0.2794 -0.1016) (xy 0.2794 0.9906) (xy -0.2794 0.9906)
			)
			(stroke
				(width 0)
				(type default)
			)
			(fill no)
			(layer "F.CrtYd")
		)
		(fp_line
			(start -0.2794 -0.1016)
			(end -0.2794 0.9906)
			(stroke
				(width 0.1)
				(type default)
			)
			(layer "F.Fab")
		)
		(fp_line
			(start -0.2794 0.9906)
			(end 0.2794 0.9906)
			(stroke
				(width 0.1)
				(type default)
			)
			(layer "F.Fab")
		)
		(fp_line
			(start 0.2794 -0.1016)
			(end -0.2794 -0.1016)
			(stroke
				(width 0.1)
				(type default)
			)
			(layer "F.Fab")
		)
		(fp_line
			(start 0.2794 0.9906)
			(end 0.2794 -0.1016)
			(stroke
				(width 0.1)
				(type default)
			)
			(layer "F.Fab")
		)
		(pad "1" smd rect
			(at 0 0)
			(size 0.508 0.508)
			(layers "F.Cu" "F.Mask" "F.Paste")
			(net "P3V3_STBY")
		)
		(pad "2" smd rect
			(at 0 0.889)
			(size 0.508 0.508)
			(layers "F.Cu" "F.Mask" "F.Paste")
			(net "IRQ_LOM_ALERT_N")
		)
		(zone
			(layer "F.Cu")
			(hatch none 0.5)
			(connect_pads
				(clearance 0)
			)
			(min_thickness 0.25)
			(keepout
				(tracks allowed)
				(vias not_allowed)
				(pads allowed)
				(copperpour not_allowed)
				(footprints allowed)
			)
			(placement
				(enabled no)
				(sheetname "")
			)
			(fill
				(thermal_gap 0.5)
				(thermal_bridge_width 0.5)
				(island_removal_mode 0)
			)
			(polygon
				(pts
					(xy 477.6216 -48.7299) (xy 478.1296 -48.7299) (xy 478.1296 -48.3489) (xy 477.6216 -48.3489)
				)
			)
		)
		(zone
			(layer "F.Cu")
			(hatch none 0.5)
			(connect_pads
				(clearance 0)
			)
			(min_thickness 0.25)
			(keepout
				(tracks not_allowed)
				(vias allowed)
				(pads allowed)
				(copperpour not_allowed)
				(footprints allowed)
			)
			(placement
				(enabled no)
				(sheetname "")
			)
			(fill
				(thermal_gap 0.5)
				(thermal_bridge_width 0.5)
				(island_removal_mode 0)
			)
			(polygon
				(pts
					(xy 477.6216 -48.3489) (xy 478.1296 -48.3489) (xy 478.1296 -48.7299) (xy 477.6216 -48.7299)
				)
			)
		)
	)
)
